# S9S_MB_2U (Grand Teton) — schematic netlist excerpt (pin names and nets, part order shuffled) for the footprints in the layout excerpt that follows; sources: Cadence DE-HDL packaged netlist, KiCad conversion of 03242023_DA0F0TMBIJ0_F0T_Motherboard_J_brd_V01_OCP.brd

R1930  Q_RES  10K 1% CHIP  pkg 0402LF  page 153 : A = GND ; B = OCP_SFF_MAIN_PWR_EN
C2294  Q_CAP  0.1UF 25V 10% EMPTY  pkg 0402  page 245 : A = PDB_PRSNT_N ; B = GND

(kicad_pcb
	(version 20260206)
	(generator "pcbnew")
	(generator_version "10.0")
	(general
		(thickness 1.6)
		(legacy_teardrops no)
	)
	(paper "A4")
	(title_block
		(title "03242023_DA0F0TMBIJ0_F0T_Motherboard_J_brd_V01_OCP.brd")
		(comment 1 "Grand Teton / footprints 4174-4175 of 6105")
	)
	(layers
		(0 "F.Cu" signal "TOP")
		(4 "In1.Cu" signal "GND")
		(6 "In2.Cu" signal "IN1")
		(8 "In3.Cu" signal "GND1")
		(10 "In4.Cu" signal "IN2")
		(12 "In5.Cu" signal "GND2")
		(14 "In6.Cu" signal "IN3")
		(16 "In7.Cu" signal "GND3")
		(18 "In8.Cu" signal "VCC")
		(20 "In9.Cu" signal "VCC1")
		(22 "In10.Cu" signal "GND4")
		(24 "In11.Cu" signal "IN4")
		(26 "In12.Cu" signal "GND5")
		(28 "In13.Cu" signal "IN5")
		(30 "In14.Cu" signal "GND6")
		(32 "In15.Cu" signal "IN6")
		(34 "In16.Cu" signal "GND7")
		(2 "B.Cu" signal "BOTTOM")
		(9 "F.Adhes" user "F.Adhesive")
		(11 "B.Adhes" user "B.Adhesive")
		(13 "F.Paste" user "Package Geometry/Pastemask Top")
		(15 "B.Paste" user "Package Geometry/Pastemask Bottom")
		(5 "F.SilkS" user "Ref Des/Silkscreen Top")
		(7 "B.SilkS" user "Ref Des/Silkscreen Bottom")
		(1 "F.Mask" user "Board Geometry/Soldermask Top")
		(3 "B.Mask" user "Board Geometry/Soldermask Bottom")
		(17 "Dwgs.User" user "User.Drawings")
		(19 "Cmts.User" user "User.Comments")
		(21 "Eco1.User" user "User.Eco1")
		(23 "Eco2.User" user "User.Eco2")
		(25 "Edge.Cuts" user "Board Geometry/Outline")
		(27 "Margin" user)
		(31 "F.CrtYd" user "Package Geometry/Place Bound Top")
		(29 "B.CrtYd" user "Package Geometry/Place Bound Bottom")
		(35 "F.Fab" user "Ref Des/Assembly Top")
		(33 "B.Fab" user "Ref Des/Assembly Bottom")
	)
	(footprint ""
		(layer "B.Cu")
		(at 234.26928 -423.001948 90)
		(property "Reference" "C2294"
			(at 0 0 90)
			(layer "B.SilkS")
			(hide yes)
			(effects
				(font
					(size 1.27 1.27)
				)
				(justify mirror)
			)
		)
		(property "Value" ""
			(at 0 0 90)
			(layer "B.Fab")
			(effects
				(font
					(size 1.27 1.27)
				)
				(justify mirror)
			)
		)
		(duplicate_pad_numbers_are_jumpers no)
		(fp_line
			(start 0.7874 -0.4064)
			(end -0.7874 -0.4064)
			(stroke
				(width 0.1524)
				(type default)
			)
			(layer "B.SilkS")
		)
		(fp_line
			(start -0.7874 -0.4064)
			(end -0.7874 0.4064)
			(stroke
				(width 0.1524)
				(type default)
			)
			(layer "B.SilkS")
		)
		(fp_line
			(start 0.7874 0.4064)
			(end 0.7874 -0.4064)
			(stroke
				(width 0.1524)
				(type default)
			)
			(layer "B.SilkS")
		)
		(fp_line
			(start -0.7874 0.4064)
			(end 0.7874 0.4064)
			(stroke
				(width 0.1524)
				(type default)
			)
			(layer "B.SilkS")
		)
		(fp_line
			(start 0.67945 -0.305054)
			(end 0.12065 -0.305054)
			(stroke
				(width 0.1)
				(type default)
			)
			(layer "B.Fab")
		)
		(fp_line
			(start 0.12065 -0.305054)
			(end 0.12065 -0.2794)
			(stroke
				(width 0.1)
				(type default)
			)
			(layer "B.Fab")
		)
		(fp_line
			(start -0.12065 -0.3048)
			(end -0.67945 -0.3048)
			(stroke
				(width 0.1)
				(type default)
			)
			(layer "B.Fab")
		)
		(fp_line
			(start -0.67945 -0.3048)
			(end -0.67945 0.3048)
			(stroke
				(width 0.1)
				(type default)
			)
			(layer "B.Fab")
		)
		(fp_line
			(start 0.12065 -0.2794)
			(end -0.12065 -0.2794)
			(stroke
				(width 0.1)
				(type default)
			)
			(layer "B.Fab")
		)
		(fp_line
			(start -0.12065 -0.2794)
			(end -0.12065 -0.3048)
			(stroke
				(width 0.1)
				(type default)
			)
			(layer "B.Fab")
		)
		(fp_line
			(start 0.12065 0.2794)
			(end 0.12065 0.3048)
			(stroke
				(width 0.1)
				(type default)
			)
			(layer "B.Fab")
		)
		(fp_line
			(start -0.120396 0.2794)
			(end 0.12065 0.2794)
			(stroke
				(width 0.1)
				(type default)
			)
			(layer "B.Fab")
		)
		(fp_line
			(start 0.67945 0.3048)
			(end 0.67945 -0.305054)
			(stroke
				(width 0.1)
				(type default)
			)
			(layer "B.Fab")
		)
		(fp_line
			(start 0.12065 0.3048)
			(end 0.67945 0.3048)
			(stroke
				(width 0.1)
				(type default)
			)
			(layer "B.Fab")
		)
		(fp_line
			(start -0.120396 0.3048)
			(end -0.120396 0.2794)
			(stroke
				(width 0.1)
				(type default)
			)
			(layer "B.Fab")
		)
		(fp_line
			(start -0.67945 0.3048)
			(end -0.120396 0.3048)
			(stroke
				(width 0.1)
				(type default)
			)
			(layer "B.Fab")
		)
		(pad "1" smd circle
			(at 0.40005 0 270)
			(size 0 0)
			(layers "B.Cu" "B.Mask" "B.Paste")
			(net "PDB_PRSNT_N")
		)
		(pad "2" smd circle
			(at -0.40005 0 270)
			(size 0 0)
			(layers "B.Cu" "B.Mask" "B.Paste")
			(net "GND")
		)
	)
	(footprint ""
		(layer "B.Cu")
		(at 455.093324 -13.09116 90)
		(property "Reference" "R1930"
			(at 0 0 90)
			(layer "B.SilkS")
			(hide yes)
			(effects
				(font
					(size 1.27 1.27)
				)
				(justify mirror)
			)
		)
		(property "Value" ""
			(at 0 0 90)
			(layer "B.Fab")
			(effects
				(font
					(size 1.27 1.27)
				)
				(justify mirror)
			)
		)
		(duplicate_pad_numbers_are_jumpers no)
		(fp_line
			(start 0.7874 -0.4064)
			(end -0.7874 -0.4064)
			(stroke
				(width 0.1524)
				(type default)
			)
			(layer "B.SilkS")
		)
		(fp_line
			(start -0.7874 -0.4064)
			(end -0.7874 0.4064)
			(stroke
				(width 0.1524)
				(type default)
			)
			(layer "B.SilkS")
		)
		(fp_line
			(start 0.7874 0.4064)
			(end 0.7874 -0.4064)
			(stroke
				(width 0.1524)
				(type default)
			)
			(layer "B.SilkS")
		)
		(fp_line
			(start -0.7874 0.4064)
			(end 0.7874 0.4064)
			(stroke
				(width 0.1524)
				(type default)
			)
			(layer "B.SilkS")
		)
		(fp_line
			(start 0.67945 -0.305054)
			(end 0.12065 -0.305054)
			(stroke
				(width 0.1)
				(type default)
			)
			(layer "B.Fab")
		)
		(fp_line
			(start 0.12065 -0.305054)
			(end 0.12065 -0.2794)
			(stroke
				(width 0.1)
				(type default)
			)
			(layer "B.Fab")
		)
		(fp_line
			(start -0.12065 -0.3048)
			(end -0.67945 -0.3048)
			(stroke
				(width 0.1)
				(type default)
			)
			(layer "B.Fab")
		)
		(fp_line
			(start -0.67945 -0.3048)
			(end -0.67945 0.3048)
			(stroke
				(width 0.1)
				(type default)
			)
			(layer "B.Fab")
		)
		(fp_line
			(start 0.12065 -0.2794)
			(end -0.12065 -0.2794)
			(stroke
				(width 0.1)
				(type default)
			)
			(layer "B.Fab")
		)
		(fp_line
			(start -0.12065 -0.2794)
			(end -0.12065 -0.3048)
			(stroke
				(width 0.1)
				(type default)
			)
			(layer "B.Fab")
		)
		(fp_line
			(start 0.12065 0.2794)
			(end 0.12065 0.3048)
			(stroke
				(width 0.1)
				(type default)
			)
			(layer "B.Fab")
		)
		(fp_line
			(start -0.120396 0.2794)
			(end 0.12065 0.2794)
			(stroke
				(width 0.1)
				(type default)
			)
			(layer "B.Fab")
		)
		(fp_line
			(start 0.67945 0.3048)
			(end 0.67945 -0.305054)
			(stroke
				(width 0.1)
				(type default)
			)
			(layer "B.Fab")
		)
		(fp_line
			(start 0.12065 0.3048)
			(end 0.67945 0.3048)
			(stroke
				(width 0.1)
				(type default)
			)
			(layer "B.Fab")
		)
		(fp_line
			(start -0.120396 0.3048)
			(end -0.120396 0.2794)
			(stroke
				(width 0.1)
				(type default)
			)
			(layer "B.Fab")
		)
		(fp_line
			(start -0.67945 0.3048)
			(end -0.120396 0.3048)
			(stroke
				(width 0.1)
				(type default)
			)
			(layer "B.Fab")
		)
		(pad "1" smd circle
			(at 0.40005 0 270)
			(size 0 0)
			(layers "B.Cu" "B.Mask" "B.Paste")
			(net "GND")
		)
		(pad "2" smd circle
			(at -0.40005 0 270)
			(size 0 0)
			(layers "B.Cu" "B.Mask" "B.Paste")
			(net "OCP_SFF_MAIN_PWR_EN")
		)
	)
)
